# S9S_MB_2U (Grand Teton) — schematic netlist excerpt (pin names and nets, part order shuffled) for the footprints in the layout excerpt that follows; sources: Cadence DE-HDL packaged netlist, KiCad conversion of 03242023_DA0F0TMBIJ0_F0T_Motherboard_J_brd_V01_OCP.brd

C2359  Q_CAP  0.22UF 25V 10% X7R  pkg C0402  page 260 : A = PWRGD_P5V_ISO_R ; B = GND
C1253  Q_CAP  1UF 6.3V 10% EMPTY  pkg 0402  page 189 : A = P1V8_PCH_AUX ; B = GND

(kicad_pcb
	(version 20260206)
	(generator "pcbnew")
	(generator_version "10.0")
	(general
		(thickness 1.6)
		(legacy_teardrops no)
	)
	(paper "A4")
	(title_block
		(title "03242023_DA0F0TMBIJ0_F0T_Motherboard_J_brd_V01_OCP.brd")
		(comment 1 "Grand Teton / footprints 4552-4553 of 6105")
	)
	(layers
		(0 "F.Cu" signal "TOP")
		(4 "In1.Cu" signal "GND")
		(6 "In2.Cu" signal "IN1")
		(8 "In3.Cu" signal "GND1")
		(10 "In4.Cu" signal "IN2")
		(12 "In5.Cu" signal "GND2")
		(14 "In6.Cu" signal "IN3")
		(16 "In7.Cu" signal "GND3")
		(18 "In8.Cu" signal "VCC")
		(20 "In9.Cu" signal "VCC1")
		(22 "In10.Cu" signal "GND4")
		(24 "In11.Cu" signal "IN4")
		(26 "In12.Cu" signal "GND5")
		(28 "In13.Cu" signal "IN5")
		(30 "In14.Cu" signal "GND6")
		(32 "In15.Cu" signal "IN6")
		(34 "In16.Cu" signal "GND7")
		(2 "B.Cu" signal "BOTTOM")
		(9 "F.Adhes" user "F.Adhesive")
		(11 "B.Adhes" user "B.Adhesive")
		(13 "F.Paste" user "Package Geometry/Pastemask Top")
		(15 "B.Paste" user "Package Geometry/Pastemask Bottom")
		(5 "F.SilkS" user "Ref Des/Silkscreen Top")
		(7 "B.SilkS" user "Ref Des/Silkscreen Bottom")
		(1 "F.Mask" user "Board Geometry/Soldermask Top")
		(3 "B.Mask" user "Board Geometry/Soldermask Bottom")
		(17 "Dwgs.User" user "User.Drawings")
		(19 "Cmts.User" user "User.Comments")
		(21 "Eco1.User" user "User.Eco1")
		(23 "Eco2.User" user "User.Eco2")
		(25 "Edge.Cuts" user "Board Geometry/Outline")
		(27 "Margin" user)
		(31 "F.CrtYd" user "Package Geometry/Place Bound Top")
		(29 "B.CrtYd" user "Package Geometry/Place Bound Bottom")
		(35 "F.Fab" user "Ref Des/Assembly Top")
		(33 "B.Fab" user "Ref Des/Assembly Bottom")
	)
	(footprint ""
		(layer "B.Cu")
		(at 334.62849 -50.314352)
		(property "Reference" "C1253"
			(at 0 0 0)
			(layer "B.SilkS")
			(hide yes)
			(effects
				(font
					(size 1.27 1.27)
				)
				(justify mirror)
			)
		)
		(property "Value" ""
			(at 0 0 0)
			(layer "B.Fab")
			(effects
				(font
					(size 1.27 1.27)
				)
				(justify mirror)
			)
		)
		(duplicate_pad_numbers_are_jumpers no)
		(fp_line
			(start -0.7874 -0.4064)
			(end -0.7874 0.4064)
			(stroke
				(width 0.1524)
				(type default)
			)
			(layer "B.SilkS")
		)
		(fp_line
			(start -0.7874 0.4064)
			(end 0.7874 0.4064)
			(stroke
				(width 0.1524)
				(type default)
			)
			(layer "B.SilkS")
		)
		(fp_line
			(start 0.7874 -0.4064)
			(end -0.7874 -0.4064)
			(stroke
				(width 0.1524)
				(type default)
			)
			(layer "B.SilkS")
		)
		(fp_line
			(start 0.7874 0.4064)
			(end 0.7874 -0.4064)
			(stroke
				(width 0.1524)
				(type default)
			)
			(layer "B.SilkS")
		)
		(fp_line
			(start -0.67945 -0.3048)
			(end -0.67945 0.3048)
			(stroke
				(width 0.1)
				(type default)
			)
			(layer "B.Fab")
		)
		(fp_line
			(start -0.67945 0.3048)
			(end -0.120396 0.3048)
			(stroke
				(width 0.1)
				(type default)
			)
			(layer "B.Fab")
		)
		(fp_line
			(start -0.12065 -0.3048)
			(end -0.67945 -0.3048)
			(stroke
				(width 0.1)
				(type default)
			)
			(layer "B.Fab")
		)
		(fp_line
			(start -0.12065 -0.2794)
			(end -0.12065 -0.3048)
			(stroke
				(width 0.1)
				(type default)
			)
			(layer "B.Fab")
		)
		(fp_line
			(start -0.120396 0.2794)
			(end 0.12065 0.2794)
			(stroke
				(width 0.1)
				(type default)
			)
			(layer "B.Fab")
		)
		(fp_line
			(start -0.120396 0.3048)
			(end -0.120396 0.2794)
			(stroke
				(width 0.1)
				(type default)
			)
			(layer "B.Fab")
		)
		(fp_line
			(start 0.12065 -0.305054)
			(end 0.12065 -0.2794)
			(stroke
				(width 0.1)
				(type default)
			)
			(layer "B.Fab")
		)
		(fp_line
			(start 0.12065 -0.2794)
			(end -0.12065 -0.2794)
			(stroke
				(width 0.1)
				(type default)
			)
			(layer "B.Fab")
		)
		(fp_line
			(start 0.12065 0.2794)
			(end 0.12065 0.3048)
			(stroke
				(width 0.1)
				(type default)
			)
			(layer "B.Fab")
		)
		(fp_line
			(start 0.12065 0.3048)
			(end 0.67945 0.3048)
			(stroke
				(width 0.1)
				(type default)
			)
			(layer "B.Fab")
		)
		(fp_line
			(start 0.67945 -0.305054)
			(end 0.12065 -0.305054)
			(stroke
				(width 0.1)
				(type default)
			)
			(layer "B.Fab")
		)
		(fp_line
			(start 0.67945 0.3048)
			(end 0.67945 -0.305054)
			(stroke
				(width 0.1)
				(type default)
			)
			(layer "B.Fab")
		)
		(pad "1" smd circle
			(at 0.40005 0 180)
			(size 0 0)
			(layers "B.Cu" "B.Mask" "B.Paste")
			(net "P1V8_PCH_AUX")
		)
		(pad "2" smd circle
			(at -0.40005 0 180)
			(size 0 0)
			(layers "B.Cu" "B.Mask" "B.Paste")
			(net "GND")
		)
	)
	(footprint ""
		(layer "B.Cu")
		(at 430.8221 -51.42738 180)
		(property "Reference" "C2359"
			(at 0 0 0)
			(layer "B.SilkS")
			(hide yes)
			(effects
				(font
					(size 1.27 1.27)
				)
				(justify mirror)
			)
		)
		(property "Value" ""
			(at 0 0 0)
			(layer "B.Fab")
			(effects
				(font
					(size 1.27 1.27)
				)
				(justify mirror)
			)
		)
		(duplicate_pad_numbers_are_jumpers no)
		(fp_line
			(start 0.7874 0.4064)
			(end 0.7874 -0.4064)
			(stroke
				(width 0.1524)
				(type default)
			)
			(layer "B.SilkS")
		)
		(fp_line
			(start 0.7874 -0.4064)
			(end -0.7874 -0.4064)
			(stroke
				(width 0.1524)
				(type default)
			)
			(layer "B.SilkS")
		)
		(fp_line
			(start -0.7874 0.4064)
			(end 0.7874 0.4064)
			(stroke
				(width 0.1524)
				(type default)
			)
			(layer "B.SilkS")
		)
		(fp_line
			(start -0.7874 -0.4064)
			(end -0.7874 0.4064)
			(stroke
				(width 0.1524)
				(type default)
			)
			(layer "B.SilkS")
		)
		(fp_line
			(start 0.67945 0.3048)
			(end 0.67945 -0.305054)
			(stroke
				(width 0.1)
				(type default)
			)
			(layer "B.Fab")
		)
		(fp_line
			(start 0.67945 -0.305054)
			(end 0.12065 -0.305054)
			(stroke
				(width 0.1)
				(type default)
			)
			(layer "B.Fab")
		)
		(fp_line
			(start 0.12065 0.3048)
			(end 0.67945 0.3048)
			(stroke
				(width 0.1)
				(type default)
			)
			(layer "B.Fab")
		)
		(fp_line
			(start 0.12065 0.2794)
			(end 0.12065 0.3048)
			(stroke
				(width 0.1)
				(type default)
			)
			(layer "B.Fab")
		)
		(fp_line
			(start 0.12065 -0.2794)
			(end -0.12065 -0.2794)
			(stroke
				(width 0.1)
				(type default)
			)
			(layer "B.Fab")
		)
		(fp_line
			(start 0.12065 -0.305054)
			(end 0.12065 -0.2794)
			(stroke
				(width 0.1)
				(type default)
			)
			(layer "B.Fab")
		)
		(fp_line
			(start -0.120396 0.3048)
			(end -0.120396 0.2794)
			(stroke
				(width 0.1)
				(type default)
			)
			(layer "B.Fab")
		)
		(fp_line
			(start -0.120396 0.2794)
			(end 0.12065 0.2794)
			(stroke
				(width 0.1)
				(type default)
			)
			(layer "B.Fab")
		)
		(fp_line
			(start -0.12065 -0.2794)
			(end -0.12065 -0.3048)
			(stroke
				(width 0.1)
				(type default)
			)
			(layer "B.Fab")
		)
		(fp_line
			(start -0.12065 -0.3048)
			(end -0.67945 -0.3048)
			(stroke
				(width 0.1)
				(type default)
			)
			(layer "B.Fab")
		)
		(fp_line
			(start -0.67945 0.3048)
			(end -0.120396 0.3048)
			(stroke
				(width 0.1)
				(type default)
			)
			(layer "B.Fab")
		)
		(fp_line
			(start -0.67945 -0.3048)
			(end -0.67945 0.3048)
			(stroke
				(width 0.1)
				(type default)
			)
			(layer "B.Fab")
		)
		(pad "1" smd circle
			(at 0.40005 0)
			(size 0 0)
			(layers "B.Cu" "B.Mask" "B.Paste")
			(net "PWRGD_P5V_ISO_R")
		)
		(pad "2" smd circle
			(at -0.40005 0)
			(size 0 0)
			(layers "B.Cu" "B.Mask" "B.Paste")
			(net "GND")
		)
	)
)
